(kicad_pcb
	(version 20260206)
	(generator "pcbnew")
	(generator_version "10.0")
	(general
		(thickness 1.6)
		(legacy_teardrops no)
	)
	(paper "A4")
	(title_block
		(title "03242023_DA0F0TMBIJ0_F0T_Motherboard_J_brd_V01_OCP.brd")
		(comment 1 "Grand Teton / footprints 5130-5136 of 6105")
	)
	(layers
		(0 "F.Cu" signal "TOP")
		(4 "In1.Cu" signal "GND")
		(6 "In2.Cu" signal "IN1")
		(8 "In3.Cu" signal "GND1")
		(10 "In4.Cu" signal "IN2")
		(12 "In5.Cu" signal "GND2")
		(14 "In6.Cu" signal "IN3")
		(16 "In7.Cu" signal "GND3")
		(18 "In8.Cu" signal "VCC")
		(20 "In9.Cu" signal "VCC1")
		(22 "In10.Cu" signal "GND4")
		(24 "In11.Cu" signal "IN4")
		(26 "In12.Cu" signal "GND5")
		(28 "In13.Cu" signal "IN5")
		(30 "In14.Cu" signal "GND6")
		(32 "In15.Cu" signal "IN6")
		(34 "In16.Cu" signal "GND7")
		(2 "B.Cu" signal "BOTTOM")
		(9 "F.Adhes" user "F.Adhesive")
		(11 "B.Adhes" user "B.Adhesive")
		(13 "F.Paste" user "Package Geometry/Pastemask Top")
		(15 "B.Paste" user "Package Geometry/Pastemask Bottom")
		(5 "F.SilkS" user "Ref Des/Silkscreen Top")
		(7 "B.SilkS" user "Ref Des/Silkscreen Bottom")
		(1 "F.Mask" user "Board Geometry/Soldermask Top")
		(3 "B.Mask" user "Board Geometry/Soldermask Bottom")
		(17 "Dwgs.User" user "User.Drawings")
		(19 "Cmts.User" user "User.Comments")
		(21 "Eco1.User" user "User.Eco1")
		(23 "Eco2.User" user "User.Eco2")
		(25 "Edge.Cuts" user "Board Geometry/Outline")
		(27 "Margin" user)
		(31 "F.CrtYd" user "Package Geometry/Place Bound Top")
		(29 "B.CrtYd" user "Package Geometry/Place Bound Bottom")
		(35 "F.Fab" user "Ref Des/Assembly Top")
		(33 "B.Fab" user "Ref Des/Assembly Bottom")
	)
	(footprint ""
		(layer "B.Cu")
		(at 183.960008 -404.853902 180)
		(property "Reference" "R3924"
			(at 0 0 0)
			(layer "B.SilkS")
			(hide yes)
			(effects
				(font
					(size 1.27 1.27)
				)
				(justify mirror)
			)
		)
		(property "Value" ""
			(at 0 0 0)
			(layer "B.Fab")
			(effects
				(font
					(size 1.27 1.27)
				)
				(justify mirror)
			)
		)
		(duplicate_pad_numbers_are_jumpers no)
		(fp_line
			(start 0.7874 0.4064)
			(end 0.7874 -0.4064)
			(stroke
				(width 0.1524)
				(type default)
			)
			(layer "B.SilkS")
		)
		(fp_line
			(start 0.7874 -0.4064)
			(end -0.7874 -0.4064)
			(stroke
				(width 0.1524)
				(type default)
			)
			(layer "B.SilkS")
		)
		(fp_line
			(start -0.7874 0.4064)
			(end 0.7874 0.4064)
			(stroke
				(width 0.1524)
				(type default)
			)
			(layer "B.SilkS")
		)
		(fp_line
			(start -0.7874 -0.4064)
			(end -0.7874 0.4064)
			(stroke
				(width 0.1524)
				(type default)
			)
			(layer "B.SilkS")
		)
		(fp_line
			(start 0.67945 0.3048)
			(end 0.67945 -0.305054)
			(stroke
				(width 0.1)
				(type default)
			)
			(layer "B.Fab")
		)
		(fp_line
			(start 0.67945 -0.305054)
			(end 0.12065 -0.305054)
			(stroke
				(width 0.1)
				(type default)
			)
			(layer "B.Fab")
		)
		(fp_line
			(start 0.12065 0.3048)
			(end 0.67945 0.3048)
			(stroke
				(width 0.1)
				(type default)
			)
			(layer "B.Fab")
		)
		(fp_line
			(start 0.12065 0.2794)
			(end 0.12065 0.3048)
			(stroke
				(width 0.1)
				(type default)
			)
			(layer "B.Fab")
		)
		(fp_line
			(start 0.12065 -0.2794)
			(end -0.12065 -0.2794)
			(stroke
				(width 0.1)
				(type default)
			)
			(layer "B.Fab")
		)
		(fp_line
			(start 0.12065 -0.305054)
			(end 0.12065 -0.2794)
			(stroke
				(width 0.1)
				(type default)
			)
			(layer "B.Fab")
		)
		(fp_line
			(start -0.120396 0.3048)
			(end -0.120396 0.2794)
			(stroke
				(width 0.1)
				(type default)
			)
			(layer "B.Fab")
		)
		(fp_line
			(start -0.120396 0.2794)
			(end 0.12065 0.2794)
			(stroke
				(width 0.1)
				(type default)
			)
			(layer "B.Fab")
		)
		(fp_line
			(start -0.12065 -0.2794)
			(end -0.12065 -0.3048)
			(stroke
				(width 0.1)
				(type default)
			)
			(layer "B.Fab")
		)
		(fp_line
			(start -0.12065 -0.3048)
			(end -0.67945 -0.3048)
			(stroke
				(width 0.1)
				(type default)
			)
			(layer "B.Fab")
		)
		(fp_line
			(start -0.67945 0.3048)
			(end -0.120396 0.3048)
			(stroke
				(width 0.1)
				(type default)
			)
			(layer "B.Fab")
		)
		(fp_line
			(start -0.67945 -0.3048)
			(end -0.67945 0.3048)
			(stroke
				(width 0.1)
				(type default)
			)
			(layer "B.Fab")
		)
		(pad "1" smd circle
			(at 0.40005 0)
			(size 0 0)
			(layers "B.Cu" "B.Mask" "B.Paste")
			(net "IRQ_SML1_PMBUS_ALERT_N")
		)
		(pad "2" smd circle
			(at -0.40005 0)
			(size 0 0)
			(layers "B.Cu" "B.Mask" "B.Paste")
			(net "IRQ_SML1_PMBUS_ALERT")
		)
	)
	(footprint ""
		(layer "B.Cu")
		(at 352.402902 -212.049614)
		(property "Reference" "C512"
			(at 0 0 0)
			(layer "B.SilkS")
			(hide yes)
			(effects
				(font
					(size 1.27 1.27)
				)
				(justify mirror)
			)
		)
		(property "Value" ""
			(at 0 0 0)
			(layer "B.Fab")
			(effects
				(font
					(size 1.27 1.27)
				)
				(justify mirror)
			)
		)
		(duplicate_pad_numbers_are_jumpers no)
		(fp_line
			(start -1.524 -0.762)
			(end -1.524 0.762)
			(stroke
				(width 0.1524)
				(type default)
			)
			(layer "B.SilkS")
		)
		(fp_line
			(start -1.524 0.762)
			(end 1.524 0.762)
			(stroke
				(width 0.1524)
				(type default)
			)
			(layer "B.SilkS")
		)
		(fp_line
			(start 1.524 -0.762)
			(end -1.524 -0.762)
			(stroke
				(width 0.1524)
				(type default)
			)
			(layer "B.SilkS")
		)
		(fp_line
			(start 1.524 0.762)
			(end 1.524 -0.762)
			(stroke
				(width 0.1524)
				(type default)
			)
			(layer "B.SilkS")
		)
		(fp_line
			(start -1.1049 -0.724916)
			(end 1.1049 -0.724916)
			(stroke
				(width 0.1)
				(type default)
			)
			(layer "B.Fab")
		)
		(fp_line
			(start -1.1049 0.724916)
			(end -1.1049 -0.724916)
			(stroke
				(width 0.1)
				(type default)
			)
			(layer "B.Fab")
		)
		(fp_line
			(start 1.1049 -0.724916)
			(end 1.1049 0.724916)
			(stroke
				(width 0.1)
				(type default)
			)
			(layer "B.Fab")
		)
		(fp_line
			(start 1.1049 0.724916)
			(end -1.1049 0.724916)
			(stroke
				(width 0.1)
				(type default)
			)
			(layer "B.Fab")
		)
		(pad "1" smd rect
			(at 0.889 0)
			(size 1.016 1.27)
			(layers "B.Cu" "B.Mask" "B.Paste")
			(net "PVCCFA_EHV_CPU0")
		)
		(pad "2" smd rect
			(at -0.889 0)
			(size 1.016 1.27)
			(layers "B.Cu" "B.Mask" "B.Paste")
			(net "GND")
		)
	)
	(footprint ""
		(layer "B.Cu")
		(at 85.457284 -190.705232 -90)
		(property "Reference" "R261"
			(at 0 0 90)
			(layer "B.SilkS")
			(hide yes)
			(effects
				(font
					(size 1.27 1.27)
				)
				(justify mirror)
			)
		)
		(property "Value" ""
			(at 0 0 90)
			(layer "B.Fab")
			(effects
				(font
					(size 1.27 1.27)
				)
				(justify mirror)
			)
		)
		(duplicate_pad_numbers_are_jumpers no)
		(fp_line
			(start -0.7874 0.4064)
			(end 0.7874 0.4064)
			(stroke
				(width 0.1524)
				(type default)
			)
			(layer "B.SilkS")
		)
		(fp_line
			(start 0.7874 0.4064)
			(end 0.7874 -0.4064)
			(stroke
				(width 0.1524)
				(type default)
			)
			(layer "B.SilkS")
		)
		(fp_line
			(start -0.7874 -0.4064)
			(end -0.7874 0.4064)
			(stroke
				(width 0.1524)
				(type default)
			)
			(layer "B.SilkS")
		)
		(fp_line
			(start 0.7874 -0.4064)
			(end -0.7874 -0.4064)
			(stroke
				(width 0.1524)
				(type default)
			)
			(layer "B.SilkS")
		)
		(fp_line
			(start -0.67945 0.3048)
			(end -0.120396 0.3048)
			(stroke
				(width 0.1)
				(type default)
			)
			(layer "B.Fab")
		)
		(fp_line
			(start -0.120396 0.3048)
			(end -0.120396 0.2794)
			(stroke
				(width 0.1)
				(type default)
			)
			(layer "B.Fab")
		)
		(fp_line
			(start 0.12065 0.3048)
			(end 0.67945 0.3048)
			(stroke
				(width 0.1)
				(type default)
			)
			(layer "B.Fab")
		)
		(fp_line
			(start 0.67945 0.3048)
			(end 0.67945 -0.305054)
			(stroke
				(width 0.1)
				(type default)
			)
			(layer "B.Fab")
		)
		(fp_line
			(start -0.120396 0.2794)
			(end 0.12065 0.2794)
			(stroke
				(width 0.1)
				(type default)
			)
			(layer "B.Fab")
		)
		(fp_line
			(start 0.12065 0.2794)
			(end 0.12065 0.3048)
			(stroke
				(width 0.1)
				(type default)
			)
			(layer "B.Fab")
		)
		(fp_line
			(start -0.12065 -0.2794)
			(end -0.12065 -0.3048)
			(stroke
				(width 0.1)
				(type default)
			)
			(layer "B.Fab")
		)
		(fp_line
			(start 0.12065 -0.2794)
			(end -0.12065 -0.2794)
			(stroke
				(width 0.1)
				(type default)
			)
			(layer "B.Fab")
		)
		(fp_line
			(start -0.67945 -0.3048)
			(end -0.67945 0.3048)
			(stroke
				(width 0.1)
				(type default)
			)
			(layer "B.Fab")
		)
		(fp_line
			(start -0.12065 -0.3048)
			(end -0.67945 -0.3048)
			(stroke
				(width 0.1)
				(type default)
			)
			(layer "B.Fab")
		)
		(fp_line
			(start 0.12065 -0.305054)
			(end 0.12065 -0.2794)
			(stroke
				(width 0.1)
				(type default)
			)
			(layer "B.Fab")
		)
		(fp_line
			(start 0.67945 -0.305054)
			(end 0.12065 -0.305054)
			(stroke
				(width 0.1)
				(type default)
			)
			(layer "B.Fab")
		)
		(pad "1" smd circle
			(at 0.40005 0 90)
			(size 0 0)
			(layers "B.Cu" "B.Mask" "B.Paste")
			(net "PVNN_TERM_CPU1")
		)
		(pad "2" smd circle
			(at -0.40005 0 90)
			(size 0 0)
			(layers "B.Cu" "B.Mask" "B.Paste")
			(net "PU_CPU1_TXT_AGENT")
		)
	)
	(footprint ""
		(layer "B.Cu")
		(at 373.810276 -366.755426 90)
		(property "Reference" "PC1256"
			(at 0 0 90)
			(layer "B.SilkS")
			(hide yes)
			(effects
				(font
					(size 1.27 1.27)
				)
				(justify mirror)
			)
		)
		(property "Value" ""
			(at 0 0 90)
			(layer "B.Fab")
			(effects
				(font
					(size 1.27 1.27)
				)
				(justify mirror)
			)
		)
		(duplicate_pad_numbers_are_jumpers no)
		(fp_line
			(start 1.524 -0.762)
			(end -1.524 -0.762)
			(stroke
				(width 0.1524)
				(type default)
			)
			(layer "B.SilkS")
		)
		(fp_line
			(start -1.524 -0.762)
			(end -1.524 0.762)
			(stroke
				(width 0.1524)
				(type default)
			)
			(layer "B.SilkS")
		)
		(fp_line
			(start 1.524 0.762)
			(end 1.524 -0.762)
			(stroke
				(width 0.1524)
				(type default)
			)
			(layer "B.SilkS")
		)
		(fp_line
			(start -1.524 0.762)
			(end 1.524 0.762)
			(stroke
				(width 0.1524)
				(type default)
			)
			(layer "B.SilkS")
		)
		(fp_line
			(start 1.1049 -0.724916)
			(end 1.1049 0.724916)
			(stroke
				(width 0.1)
				(type default)
			)
			(layer "B.Fab")
		)
		(fp_line
			(start -1.1049 -0.724916)
			(end 1.1049 -0.724916)
			(stroke
				(width 0.1)
				(type default)
			)
			(layer "B.Fab")
		)
		(fp_line
			(start 1.1049 0.724916)
			(end -1.1049 0.724916)
			(stroke
				(width 0.1)
				(type default)
			)
			(layer "B.Fab")
		)
		(fp_line
			(start -1.1049 0.724916)
			(end -1.1049 -0.724916)
			(stroke
				(width 0.1)
				(type default)
			)
			(layer "B.Fab")
		)
		(pad "1" smd rect
			(at 0.889 0 90)
			(size 1.016 1.27)
			(layers "B.Cu" "B.Mask" "B.Paste")
			(net "PVPP_HBM_CPU0")
		)
		(pad "2" smd rect
			(at -0.889 0 90)
			(size 1.016 1.27)
			(layers "B.Cu" "B.Mask" "B.Paste")
			(net "GND")
		)
	)
	(footprint ""
		(layer "B.Cu")
		(at 440.137804 -18.27022)
		(property "Reference" "C1232"
			(at 0 0 0)
			(layer "B.SilkS")
			(hide yes)
			(effects
				(font
					(size 1.27 1.27)
				)
				(justify mirror)
			)
		)
		(property "Value" ""
			(at 0 0 0)
			(layer "B.Fab")
			(effects
				(font
					(size 1.27 1.27)
				)
				(justify mirror)
			)
		)
		(duplicate_pad_numbers_are_jumpers no)
		(fp_line
			(start -1.524 -0.762)
			(end -1.524 0.762)
			(stroke
				(width 0.1524)
				(type default)
			)
			(layer "B.SilkS")
		)
		(fp_line
			(start -1.524 0.762)
			(end 1.524 0.762)
			(stroke
				(width 0.1524)
				(type default)
			)
			(layer "B.SilkS")
		)
		(fp_line
			(start 1.524 -0.762)
			(end -1.524 -0.762)
			(stroke
				(width 0.1524)
				(type default)
			)
			(layer "B.SilkS")
		)
		(fp_line
			(start 1.524 0.762)
			(end 1.524 -0.762)
			(stroke
				(width 0.1524)
				(type default)
			)
			(layer "B.SilkS")
		)
		(fp_line
			(start -1.1049 -0.724916)
			(end 1.1049 -0.724916)
			(stroke
				(width 0.1)
				(type default)
			)
			(layer "B.Fab")
		)
		(fp_line
			(start -1.1049 0.724916)
			(end -1.1049 -0.724916)
			(stroke
				(width 0.1)
				(type default)
			)
			(layer "B.Fab")
		)
		(fp_line
			(start 1.1049 -0.724916)
			(end 1.1049 0.724916)
			(stroke
				(width 0.1)
				(type default)
			)
			(layer "B.Fab")
		)
		(fp_line
			(start 1.1049 0.724916)
			(end -1.1049 0.724916)
			(stroke
				(width 0.1)
				(type default)
			)
			(layer "B.Fab")
		)
		(pad "1" smd rect
			(at 0.889 0)
			(size 1.016 1.27)
			(layers "B.Cu" "B.Mask" "B.Paste")
			(net "P12V_OCP_SFF")
		)
		(pad "2" smd rect
			(at -0.889 0)
			(size 1.016 1.27)
			(layers "B.Cu" "B.Mask" "B.Paste")
			(net "GND")
		)
	)
	(footprint ""
		(layer "B.Cu")
		(at 179.360068 -397.188182)
		(property "Reference" "PR3929"
			(at 0 0 0)
			(layer "B.SilkS")
			(hide yes)
			(effects
				(font
					(size 1.27 1.27)
				)
				(justify mirror)
			)
		)
		(property "Value" ""
			(at 0 0 0)
			(layer "B.Fab")
			(effects
				(font
					(size 1.27 1.27)
				)
				(justify mirror)
			)
		)
		(duplicate_pad_numbers_are_jumpers no)
		(fp_line
			(start -0.7874 -0.4064)
			(end -0.7874 0.4064)
			(stroke
				(width 0.1524)
				(type default)
			)
			(layer "B.SilkS")
		)
		(fp_line
			(start -0.7874 0.4064)
			(end 0.7874 0.4064)
			(stroke
				(width 0.1524)
				(type default)
			)
			(layer "B.SilkS")
		)
		(fp_line
			(start 0.7874 -0.4064)
			(end -0.7874 -0.4064)
			(stroke
				(width 0.1524)
				(type default)
			)
			(layer "B.SilkS")
		)
		(fp_line
			(start 0.7874 0.4064)
			(end 0.7874 -0.4064)
			(stroke
				(width 0.1524)
				(type default)
			)
			(layer "B.SilkS")
		)
		(fp_line
			(start -0.67945 -0.3048)
			(end -0.67945 0.3048)
			(stroke
				(width 0.1)
				(type default)
			)
			(layer "B.Fab")
		)
		(fp_line
			(start -0.67945 0.3048)
			(end -0.120396 0.3048)
			(stroke
				(width 0.1)
				(type default)
			)
			(layer "B.Fab")
		)
		(fp_line
			(start -0.12065 -0.3048)
			(end -0.67945 -0.3048)
			(stroke
				(width 0.1)
				(type default)
			)
			(layer "B.Fab")
		)
		(fp_line
			(start -0.12065 -0.2794)
			(end -0.12065 -0.3048)
			(stroke
				(width 0.1)
				(type default)
			)
			(layer "B.Fab")
		)
		(fp_line
			(start -0.120396 0.2794)
			(end 0.12065 0.2794)
			(stroke
				(width 0.1)
				(type default)
			)
			(layer "B.Fab")
		)
		(fp_line
			(start -0.120396 0.3048)
			(end -0.120396 0.2794)
			(stroke
				(width 0.1)
				(type default)
			)
			(layer "B.Fab")
		)
		(fp_line
			(start 0.12065 -0.305054)
			(end 0.12065 -0.2794)
			(stroke
				(width 0.1)
				(type default)
			)
			(layer "B.Fab")
		)
		(fp_line
			(start 0.12065 -0.2794)
			(end -0.12065 -0.2794)
			(stroke
				(width 0.1)
				(type default)
			)
			(layer "B.Fab")
		)
		(fp_line
			(start 0.12065 0.2794)
			(end 0.12065 0.3048)
			(stroke
				(width 0.1)
				(type default)
			)
			(layer "B.Fab")
		)
		(fp_line
			(start 0.12065 0.3048)
			(end 0.67945 0.3048)
			(stroke
				(width 0.1)
				(type default)
			)
			(layer "B.Fab")
		)
		(fp_line
			(start 0.67945 -0.305054)
			(end 0.12065 -0.305054)
			(stroke
				(width 0.1)
				(type default)
			)
			(layer "B.Fab")
		)
		(fp_line
			(start 0.67945 0.3048)
			(end 0.67945 -0.305054)
			(stroke
				(width 0.1)
				(type default)
			)
			(layer "B.Fab")
		)
		(pad "1" smd circle
			(at 0.40005 0 180)
			(size 0 0)
			(layers "B.Cu" "B.Mask" "B.Paste")
			(net "HSC_ADDR")
		)
		(pad "2" smd circle
			(at -0.40005 0 180)
			(size 0 0)
			(layers "B.Cu" "B.Mask" "B.Paste")
			(net "HSC_VDD18")
		)
	)
	(footprint ""
		(layer "B.Cu")
		(at 418.540692 -166.050214 180)
		(property "Reference" "PR1785"
			(at 0 0 0)
			(layer "B.SilkS")
			(hide yes)
			(effects
				(font
					(size 1.27 1.27)
				)
				(justify mirror)
			)
		)
		(property "Value" ""
			(at 0 0 0)
			(layer "B.Fab")
			(effects
				(font
					(size 1.27 1.27)
				)
				(justify mirror)
			)
		)
		(duplicate_pad_numbers_are_jumpers no)
		(fp_line
			(start 0.7874 0.4064)
			(end 0.7874 -0.4064)
			(stroke
				(width 0.1524)
				(type default)
			)
			(layer "B.SilkS")
		)
		(fp_line
			(start 0.7874 -0.4064)
			(end -0.7874 -0.4064)
			(stroke
				(width 0.1524)
				(type default)
			)
			(layer "B.SilkS")
		)
		(fp_line
			(start -0.7874 0.4064)
			(end 0.7874 0.4064)
			(stroke
				(width 0.1524)
				(type default)
			)
			(layer "B.SilkS")
		)
		(fp_line
			(start -0.7874 -0.4064)
			(end -0.7874 0.4064)
			(stroke
				(width 0.1524)
				(type default)
			)
			(layer "B.SilkS")
		)
		(fp_line
			(start 0.67945 0.3048)
			(end 0.67945 -0.305054)
			(stroke
				(width 0.1)
				(type default)
			)
			(layer "B.Fab")
		)
		(fp_line
			(start 0.67945 -0.305054)
			(end 0.12065 -0.305054)
			(stroke
				(width 0.1)
				(type default)
			)
			(layer "B.Fab")
		)
		(fp_line
			(start 0.12065 0.3048)
			(end 0.67945 0.3048)
			(stroke
				(width 0.1)
				(type default)
			)
			(layer "B.Fab")
		)
		(fp_line
			(start 0.12065 0.2794)
			(end 0.12065 0.3048)
			(stroke
				(width 0.1)
				(type default)
			)
			(layer "B.Fab")
		)
		(fp_line
			(start 0.12065 -0.2794)
			(end -0.12065 -0.2794)
			(stroke
				(width 0.1)
				(type default)
			)
			(layer "B.Fab")
		)
		(fp_line
			(start 0.12065 -0.305054)
			(end 0.12065 -0.2794)
			(stroke
				(width 0.1)
				(type default)
			)
			(layer "B.Fab")
		)
		(fp_line
			(start -0.120396 0.3048)
			(end -0.120396 0.2794)
			(stroke
				(width 0.1)
				(type default)
			)
			(layer "B.Fab")
		)
		(fp_line
			(start -0.120396 0.2794)
			(end 0.12065 0.2794)
			(stroke
				(width 0.1)
				(type default)
			)
			(layer "B.Fab")
		)
		(fp_line
			(start -0.12065 -0.2794)
			(end -0.12065 -0.3048)
			(stroke
				(width 0.1)
				(type default)
			)
			(layer "B.Fab")
		)
		(fp_line
			(start -0.12065 -0.3048)
			(end -0.67945 -0.3048)
			(stroke
				(width 0.1)
				(type default)
			)
			(layer "B.Fab")
		)
		(fp_line
			(start -0.67945 0.3048)
			(end -0.120396 0.3048)
			(stroke
				(width 0.1)
				(type default)
			)
			(layer "B.Fab")
		)
		(fp_line
			(start -0.67945 -0.3048)
			(end -0.67945 0.3048)
			(stroke
				(width 0.1)
				(type default)
			)
			(layer "B.Fab")
		)
		(pad "1" smd circle
			(at 0.40005 0)
			(size 0 0)
			(layers "B.Cu" "B.Mask" "B.Paste")
			(net "PVCCD_HV_CPU0_VOS")
		)
		(pad "2" smd circle
			(at -0.40005 0)
			(size 0 0)
			(layers "B.Cu" "B.Mask" "B.Paste")
			(net "PVCCD_HV_CPU0")
		)
	)
)
